# BASEBOARD_FAB2 (Tioga Pass) — schematic netlist excerpt (pin names and nets, part order shuffled) for the footprints in the layout excerpt that follows; sources: Cadence DE-HDL packaged netlist, KiCad conversion of Wiwynn_Tioga_Pass_MB.brd

R9A8  RES  0.0 5% CHIP  pkg 0402  page 155 : A = SPA_SIN_SW_R ; B = SPA_MID_DBG1_RX
C2D13  CAP_A  22.0UF 4V 20% X6S  pkg 0603V  page 76 : A = PVCCIN_CPU1 ; B = GND
R8E1  RES  0.0 5% CHIP  pkg 0402  page 184 : A = IRQ_SPI_TPM_N_R ; B = IRQ_PIRQA_SPI_TPM_N

(kicad_pcb
	(version 20260206)
	(generator "pcbnew")
	(generator_version "10.0")
	(general
		(thickness 1.6)
		(legacy_teardrops no)
	)
	(paper "A4")
	(title_block
		(title "Wiwynn_Tioga_Pass_MB.brd")
		(comment 1 "Tioga Pass / footprints 1625-1627 of 4770")
	)
	(layers
		(0 "F.Cu" signal "TOP")
		(4 "In1.Cu" signal "L2GND")
		(6 "In2.Cu" signal "L3")
		(8 "In3.Cu" signal "L4GND")
		(10 "In4.Cu" signal "L5")
		(12 "In5.Cu" signal "L6GND")
		(14 "In6.Cu" signal "L7VCC")
		(16 "In7.Cu" signal "L8VCC")
		(18 "In8.Cu" signal "L9GND")
		(20 "In9.Cu" signal "L10")
		(22 "In10.Cu" signal "L11GND")
		(24 "In11.Cu" signal "L12")
		(26 "In12.Cu" signal "L13GND")
		(2 "B.Cu" signal "BOTTOM")
		(9 "F.Adhes" user "F.Adhesive")
		(11 "B.Adhes" user "B.Adhesive")
		(13 "F.Paste" user "Package Geometry/Pastemask Top")
		(15 "B.Paste" user "Package Geometry/Pastemask Bottom")
		(5 "F.SilkS" user "Ref Des/Silkscreen Top")
		(7 "B.SilkS" user "Ref Des/Silkscreen Bottom")
		(1 "F.Mask" user "Board Geometry/Soldermask Top")
		(3 "B.Mask" user "Board Geometry/Soldermask Bottom")
		(17 "Dwgs.User" user "User.Drawings")
		(19 "Cmts.User" user "User.Comments")
		(21 "Eco1.User" user "User.Eco1")
		(23 "Eco2.User" user "User.Eco2")
		(25 "Edge.Cuts" user "Board Geometry/Outline")
		(27 "Margin" user)
		(31 "F.CrtYd" user "Package Geometry/Place Bound Top")
		(29 "B.CrtYd" user "Package Geometry/Place Bound Bottom")
		(35 "F.Fab" user "Ref Des/Assembly Top")
		(33 "B.Fab" user "Ref Des/Assembly Bottom")
	)
	(footprint ""
		(layer "F.Cu")
		(at 417.0045 -64.135 90)
		(property "Reference" "R8E1"
			(at 0 0 90)
			(layer "F.SilkS")
			(hide yes)
			(effects
				(font
					(size 1.27 1.27)
				)
			)
		)
		(property "Value" ""
			(at 0 0 90)
			(layer "F.Fab")
			(effects
				(font
					(size 1.27 1.27)
				)
			)
		)
		(duplicate_pad_numbers_are_jumpers no)
		(fp_poly
			(pts
				(xy -0.2794 -0.1016) (xy 0.2794 -0.1016) (xy 0.2794 0.9906) (xy -0.2794 0.9906)
			)
			(stroke
				(width 0)
				(type default)
			)
			(fill no)
			(layer "F.CrtYd")
		)
		(fp_line
			(start 0.2794 -0.1016)
			(end -0.2794 -0.1016)
			(stroke
				(width 0.1)
				(type default)
			)
			(layer "F.Fab")
		)
		(fp_line
			(start -0.2794 -0.1016)
			(end -0.2794 0.9906)
			(stroke
				(width 0.1)
				(type default)
			)
			(layer "F.Fab")
		)
		(fp_line
			(start 0.2794 0.9906)
			(end 0.2794 -0.1016)
			(stroke
				(width 0.1)
				(type default)
			)
			(layer "F.Fab")
		)
		(fp_line
			(start -0.2794 0.9906)
			(end 0.2794 0.9906)
			(stroke
				(width 0.1)
				(type default)
			)
			(layer "F.Fab")
		)
		(pad "1" smd rect
			(at 0 0 90)
			(size 0.508 0.508)
			(layers "F.Cu" "F.Mask" "F.Paste")
			(net "IRQ_SPI_TPM_N_R")
		)
		(pad "2" smd rect
			(at 0 0.889 90)
			(size 0.508 0.508)
			(layers "F.Cu" "F.Mask" "F.Paste")
			(net "IRQ_PIRQA_SPI_TPM_N")
		)
		(zone
			(layer "F.Cu")
			(hatch none 0.5)
			(connect_pads
				(clearance 0)
			)
			(min_thickness 0.25)
			(keepout
				(tracks allowed)
				(vias not_allowed)
				(pads allowed)
				(copperpour not_allowed)
				(footprints allowed)
			)
			(placement
				(enabled no)
				(sheetname "")
			)
			(fill
				(thermal_gap 0.5)
				(thermal_bridge_width 0.5)
				(island_removal_mode 0)
			)
			(polygon
				(pts
					(xy 417.2585 -63.881) (xy 417.2585 -64.389) (xy 417.6395 -64.389) (xy 417.6395 -63.881)
				)
			)
		)
		(zone
			(layer "F.Cu")
			(hatch none 0.5)
			(connect_pads
				(clearance 0)
			)
			(min_thickness 0.25)
			(keepout
				(tracks not_allowed)
				(vias allowed)
				(pads allowed)
				(copperpour not_allowed)
				(footprints allowed)
			)
			(placement
				(enabled no)
				(sheetname "")
			)
			(fill
				(thermal_gap 0.5)
				(thermal_bridge_width 0.5)
				(island_removal_mode 0)
			)
			(polygon
				(pts
					(xy 417.6395 -63.881) (xy 417.6395 -64.389) (xy 417.2585 -64.389) (xy 417.2585 -63.881)
				)
			)
		)
	)
	(footprint ""
		(layer "F.Cu")
		(at 490.524546 -152.91816 90)
		(property "Reference" "R9A8"
			(at 0 0 90)
			(layer "F.SilkS")
			(hide yes)
			(effects
				(font
					(size 1.27 1.27)
				)
			)
		)
		(property "Value" ""
			(at 0 0 90)
			(layer "F.Fab")
			(effects
				(font
					(size 1.27 1.27)
				)
			)
		)
		(duplicate_pad_numbers_are_jumpers no)
		(fp_poly
			(pts
				(xy -0.2794 -0.1016) (xy 0.2794 -0.1016) (xy 0.2794 0.9906) (xy -0.2794 0.9906)
			)
			(stroke
				(width 0)
				(type default)
			)
			(fill no)
			(layer "F.CrtYd")
		)
		(fp_line
			(start 0.2794 -0.1016)
			(end -0.2794 -0.1016)
			(stroke
				(width 0.1)
				(type default)
			)
			(layer "F.Fab")
		)
		(fp_line
			(start -0.2794 -0.1016)
			(end -0.2794 0.9906)
			(stroke
				(width 0.1)
				(type default)
			)
			(layer "F.Fab")
		)
		(fp_line
			(start 0.2794 0.9906)
			(end 0.2794 -0.1016)
			(stroke
				(width 0.1)
				(type default)
			)
			(layer "F.Fab")
		)
		(fp_line
			(start -0.2794 0.9906)
			(end 0.2794 0.9906)
			(stroke
				(width 0.1)
				(type default)
			)
			(layer "F.Fab")
		)
		(pad "1" smd rect
			(at 0 0 90)
			(size 0.508 0.508)
			(layers "F.Cu" "F.Mask" "F.Paste")
			(net "SPA_SIN_SW_R")
		)
		(pad "2" smd rect
			(at 0 0.889 90)
			(size 0.508 0.508)
			(layers "F.Cu" "F.Mask" "F.Paste")
			(net "SPA_MID_DBG1_RX")
		)
		(zone
			(layer "F.Cu")
			(hatch none 0.5)
			(connect_pads
				(clearance 0)
			)
			(min_thickness 0.25)
			(keepout
				(tracks allowed)
				(vias not_allowed)
				(pads allowed)
				(copperpour not_allowed)
				(footprints allowed)
			)
			(placement
				(enabled no)
				(sheetname "")
			)
			(fill
				(thermal_gap 0.5)
				(thermal_bridge_width 0.5)
				(island_removal_mode 0)
			)
			(polygon
				(pts
					(xy 490.778546 -152.66416) (xy 490.778546 -153.17216) (xy 491.159546 -153.17216) (xy 491.159546 -152.66416)
				)
			)
		)
		(zone
			(layer "F.Cu")
			(hatch none 0.5)
			(connect_pads
				(clearance 0)
			)
			(min_thickness 0.25)
			(keepout
				(tracks not_allowed)
				(vias allowed)
				(pads allowed)
				(copperpour not_allowed)
				(footprints allowed)
			)
			(placement
				(enabled no)
				(sheetname "")
			)
			(fill
				(thermal_gap 0.5)
				(thermal_bridge_width 0.5)
				(island_removal_mode 0)
			)
			(polygon
				(pts
					(xy 491.159546 -152.66416) (xy 491.159546 -153.17216) (xy 490.778546 -153.17216) (xy 490.778546 -152.66416)
				)
			)
		)
	)
	(footprint ""
		(layer "F.Cu")
		(at 98.194368 -79.6036 180)
		(property "Reference" "C2D13"
			(at 0 0 180)
			(layer "F.SilkS")
			(hide yes)
			(effects
				(font
					(size 1.27 1.27)
				)
			)
		)
		(property "Value" ""
			(at 0 0 180)
			(layer "F.Fab")
			(effects
				(font
					(size 1.27 1.27)
				)
			)
		)
		(duplicate_pad_numbers_are_jumpers no)
		(fp_poly
			(pts
				(xy -0.4953 -0.2032) (xy 0.4953 -0.2032) (xy 0.4953 1.6002) (xy -0.4953 1.6002)
			)
			(stroke
				(width 0)
				(type default)
			)
			(fill no)
			(layer "F.CrtYd")
		)
		(fp_line
			(start 0.4953 1.6002)
			(end -0.4953 1.6002)
			(stroke
				(width 0.1)
				(type default)
			)
			(layer "F.Fab")
		)
		(fp_line
			(start 0.4953 -0.2032)
			(end 0.4953 1.6002)
			(stroke
				(width 0.1)
				(type default)
			)
			(layer "F.Fab")
		)
		(fp_line
			(start -0.4953 1.6002)
			(end -0.4953 -0.2032)
			(stroke
				(width 0.1)
				(type default)
			)
			(layer "F.Fab")
		)
		(fp_line
			(start -0.4953 -0.2032)
			(end 0.4953 -0.2032)
			(stroke
				(width 0.1)
				(type default)
			)
			(layer "F.Fab")
		)
		(pad "1" smd rect
			(at 0 0 180)
			(size 0.762 0.889)
			(layers "F.Cu" "F.Mask" "F.Paste")
			(net "PVCCIN_CPU1")
		)
		(pad "2" smd rect
			(at 0 1.397 180)
			(size 0.762 0.889)
			(layers "F.Cu" "F.Mask" "F.Paste")
			(net "GND")
		)
		(zone
			(layer "F.Cu")
			(hatch none 0.5)
			(connect_pads
				(clearance 0)
			)
			(min_thickness 0.25)
			(keepout
				(tracks not_allowed)
				(vias allowed)
				(pads allowed)
				(copperpour not_allowed)
				(footprints allowed)
			)
			(placement
				(enabled no)
				(sheetname "")
			)
			(fill
				(thermal_gap 0.5)
				(thermal_bridge_width 0.5)
				(island_removal_mode 0)
			)
			(polygon
				(pts
					(xy 98.575368 -80.0481) (xy 97.813368 -80.0481) (xy 97.813368 -80.5561) (xy 98.575368 -80.5561)
				)
			)
		)
	)
)
